(kicad_pcb
	(version 20241229)
	(generator "pcbnew")
	(generator_version "9.0")
	(general
		(thickness 1.61)
		(legacy_teardrops no)
	)
	(paper "A3")
	(title_block
		(title "SO-DIMM DDR5 Tester")
		(date "2025-11-26")
		(rev "1.3.0")
		(comment 9 "footprints 192-195 of 627")
	)
	(layers
		(0 "F.Cu" signal)
		(4 "In1.Cu" power)
		(6 "In2.Cu" mixed)
		(8 "In3.Cu" power)
		(10 "In4.Cu" mixed)
		(12 "In5.Cu" power)
		(14 "In6.Cu" mixed)
		(16 "In7.Cu" power)
		(18 "In8.Cu" power)
		(20 "In9.Cu" mixed)
		(22 "In10.Cu" power)
		(2 "B.Cu" signal)
		(9 "F.Adhes" user "F.Adhesive")
		(11 "B.Adhes" user "B.Adhesive")
		(13 "F.Paste" user)
		(15 "B.Paste" user)
		(5 "F.SilkS" user "F.Silkscreen")
		(7 "B.SilkS" user "B.Silkscreen")
		(1 "F.Mask" user)
		(3 "B.Mask" user)
		(17 "Dwgs.User" user "User.Drawings")
		(19 "Cmts.User" user "User.Comments")
		(21 "Eco1.User" user "User.Eco1")
		(23 "Eco2.User" user "User.Eco2")
		(25 "Edge.Cuts" user)
		(27 "Margin" user)
		(31 "F.CrtYd" user "F.Courtyard")
		(29 "B.CrtYd" user "B.Courtyard")
		(35 "F.Fab" user)
		(33 "B.Fab" user)
	)
	(footprint "antmicro-footprints:SC70-3"
		(layer "F.Cu")
		(at 192.645 138.945)
		(property "Reference" "Q14"
			(at 0 -1.6 0)
			(layer "F.SilkS")
			(hide yes)
			(effects
				(font
					(size 0.7 0.7)
					(thickness 0.15)
				)
				(justify left bottom)
			)
		)
		(property "Value" "BSS138PW,115"
			(at 0 2.3 0)
			(layer "F.Fab")
			(effects
				(font
					(size 0.7 0.7)
					(thickness 0.15)
				)
				(justify left bottom)
			)
		)
		(property "Datasheet" "https://assets.nexperia.com/documents/data-sheet/BSS138PW.pdf"
			(at 0 0 0)
			(layer "F.Fab")
			(hide yes)
			(effects
				(font
					(size 1.27 1.27)
					(thickness 0.15)
				)
			)
		)
		(property "Description" "Power MOSFET, N Channel, 60 V, 320 mA, 0.9 ohm, SOT-323, Surface Mount"
			(at 0 0 0)
			(layer "F.Fab")
			(hide yes)
			(effects
				(font
					(size 1.27 1.27)
					(thickness 0.15)
				)
			)
		)
		(property "Author" "Antmicro"
			(at 0 0 0)
			(layer "F.Fab")
			(hide yes)
			(effects
				(font
					(size 1 1)
					(thickness 0.15)
				)
			)
		)
		(property "License" "Apache-2.0"
			(at 0 0 0)
			(layer "F.Fab")
			(hide yes)
			(effects
				(font
					(size 1 1)
					(thickness 0.15)
				)
			)
		)
		(property "MPN" "BSS138PW,115"
			(at 0 0 0)
			(layer "F.Fab")
			(hide yes)
			(effects
				(font
					(size 1 1)
					(thickness 0.15)
				)
			)
		)
		(property "Manufacturer" "Nexperia"
			(at 0 0 0)
			(layer "F.Fab")
			(hide yes)
			(effects
				(font
					(size 1 1)
					(thickness 0.15)
				)
			)
		)
		(sheetname "/Supply/")
		(sheetfile "supply.kicad_sch")
		(attr smd)
		(fp_line
			(start -0.3 -1)
			(end 0.627 -0.999)
			(stroke
				(width 0.15)
				(type solid)
			)
			(layer "F.SilkS")
		)
		(fp_line
			(start -0.3 1)
			(end 0.627 1.001)
			(stroke
				(width 0.15)
				(type solid)
			)
			(layer "F.SilkS")
		)
		(fp_line
			(start 0.627 -0.6)
			(end 0.627 -0.999)
			(stroke
				(width 0.15)
				(type solid)
			)
			(layer "F.SilkS")
		)
		(fp_line
			(start 0.627 0.6)
			(end 0.627 1.001)
			(stroke
				(width 0.15)
				(type solid)
			)
			(layer "F.SilkS")
		)
		(fp_line
			(start -1.4 1)
			(end -1.4 -1)
			(stroke
				(width 0.05)
				(type solid)
			)
			(layer "F.CrtYd")
		)
		(fp_line
			(start -0.9 -1.3)
			(end -0.9 -1)
			(stroke
				(width 0.05)
				(type solid)
			)
			(layer "F.CrtYd")
		)
		(fp_line
			(start -0.9 -1.3)
			(end 0.9 -1.3)
			(stroke
				(width 0.05)
				(type solid)
			)
			(layer "F.CrtYd")
		)
		(fp_line
			(start -0.9 -1)
			(end -1.4 -1)
			(stroke
				(width 0.05)
				(type solid)
			)
			(layer "F.CrtYd")
		)
		(fp_line
			(start -0.9 1)
			(end -1.4 1)
			(stroke
				(width 0.05)
				(type solid)
			)
			(layer "F.CrtYd")
		)
		(fp_line
			(start -0.9 1.3)
			(end -0.9 1)
			(stroke
				(width 0.05)
				(type solid)
			)
			(layer "F.CrtYd")
		)
		(fp_line
			(start 0.9 -1.3)
			(end 0.9 -0.4)
			(stroke
				(width 0.05)
				(type solid)
			)
			(layer "F.CrtYd")
		)
		(fp_line
			(start 0.9 -0.4)
			(end 1.4 -0.4)
			(stroke
				(width 0.05)
				(type solid)
			)
			(layer "F.CrtYd")
		)
		(fp_line
			(start 0.9 0.4)
			(end 0.9 1.3)
			(stroke
				(width 0.05)
				(type solid)
			)
			(layer "F.CrtYd")
		)
		(fp_line
			(start 0.9 1.3)
			(end -0.9 1.3)
			(stroke
				(width 0.05)
				(type solid)
			)
			(layer "F.CrtYd")
		)
		(fp_line
			(start 1.4 -0.4)
			(end 1.4 0.4)
			(stroke
				(width 0.05)
				(type solid)
			)
			(layer "F.CrtYd")
		)
		(fp_line
			(start 1.4 0.4)
			(end 0.9 0.4)
			(stroke
				(width 0.05)
				(type solid)
			)
			(layer "F.CrtYd")
		)
		(fp_rect
			(start -0.623 -0.999)
			(end 0.627 1.001)
			(stroke
				(width 0.15)
				(type solid)
			)
			(fill no)
			(layer "F.Fab")
		)
		(pad "1" smd rect
			(at -1.051 -0.65 90)
			(size 0.6 0.6)
			(layers "F.Cu" "F.Mask" "F.Paste")
			(net 242 "FPGA_POWER_OFF")
			(pinfunction "G")
			(pintype "input")
		)
		(pad "2" smd rect
			(at -1.051 0.65 90)
			(size 0.6 0.6)
			(layers "F.Cu" "F.Mask" "F.Paste")
			(net 1 "GND")
			(pinfunction "S")
			(pintype "passive")
		)
		(pad "3" smd rect
			(at 1.05 0 90)
			(size 0.6 0.6)
			(layers "F.Cu" "F.Mask" "F.Paste")
			(net 185 "/Supply/~{PB_CTRL_CLR}")
			(pinfunction "D")
			(pintype "passive")
		)
	)
	(footprint "antmicro-footprints:R_0402_1005Metric"
		(layer "F.Cu")
		(at 190.545 141.745 90)
		(descr "Resistor SMD 0402")
		(tags "resistor SMD 0402")
		(property "Reference" "R171"
			(at -1.122484 -0.772697 90)
			(layer "F.SilkS")
			(hide yes)
			(effects
				(font
					(size 0.7 0.7)
					(thickness 0.15)
				)
				(justify left bottom)
			)
		)
		(property "Value" "R_47k_0402"
			(at -1.011843 1.772047 90)
			(layer "F.Fab")
			(effects
				(font
					(size 0.7 0.7)
					(thickness 0.15)
				)
				(justify left bottom)
			)
		)
		(property "Datasheet" "https://www.bourns.com/docs/product-datasheets/cr.pdf"
			(at 0 0 90)
			(layer "F.Fab")
			(hide yes)
			(effects
				(font
					(size 1.27 1.27)
					(thickness 0.15)
				)
			)
		)
		(property "Author" "Antmicro"
			(at 332.29 -48.8 0)
			(layer "F.Fab")
			(hide yes)
			(effects
				(font
					(size 1 1)
					(thickness 0.15)
				)
			)
		)
		(property "License" "Apache-2.0"
			(at 332.29 -48.8 0)
			(layer "F.Fab")
			(hide yes)
			(effects
				(font
					(size 1 1)
					(thickness 0.15)
				)
			)
		)
		(property "MPN" "CR0402-FX-4702GLF"
			(at 332.29 -48.8 0)
			(layer "F.Fab")
			(hide yes)
			(effects
				(font
					(size 1 1)
					(thickness 0.15)
				)
			)
		)
		(property "Manufacturer" "Bourns"
			(at 332.29 -48.8 0)
			(layer "F.Fab")
			(hide yes)
			(effects
				(font
					(size 1 1)
					(thickness 0.15)
				)
			)
		)
		(property "Tolerance" "1%"
			(at 332.29 -48.8 0)
			(layer "F.Fab")
			(hide yes)
			(effects
				(font
					(size 1 1)
					(thickness 0.15)
				)
			)
		)
		(property "Val" "47k"
			(at 332.29 -48.8 0)
			(layer "F.Fab")
			(hide yes)
			(effects
				(font
					(size 1 1)
					(thickness 0.15)
				)
			)
		)
		(sheetname "/Supply/")
		(sheetfile "supply.kicad_sch")
		(attr smd)
		(fp_rect
			(start -0.93 -0.47)
			(end 0.93 0.47)
			(stroke
				(width 0.05)
				(type solid)
			)
			(fill no)
			(layer "F.CrtYd")
		)
		(fp_rect
			(start -0.5 -0.25)
			(end 0.5 0.25)
			(stroke
				(width 0.15)
				(type solid)
			)
			(fill no)
			(layer "F.Fab")
		)
		(pad "1" smd roundrect
			(at -0.485 0 90)
			(size 0.59 0.64)
			(layers "F.Cu" "F.Mask" "F.Paste")
			(roundrect_rratio 0.25)
			(net 1 "GND")
			(pintype "passive")
		)
		(pad "2" smd roundrect
			(at 0.485 0 90)
			(size 0.59 0.64)
			(layers "F.Cu" "F.Mask" "F.Paste")
			(roundrect_rratio 0.25)
			(net 241 "FPGA_POWER_CYCLE")
			(pintype "passive")
		)
	)
	(footprint "antmicro-footprints:LED_0603_1608Metric_G"
		(layer "F.Cu")
		(at 78.6 126.3)
		(descr "LED SMD 0603 Green")
		(tags "LED SMD 0603 Green")
		(property "Reference" "D1"
			(at -0.001 -0.901 0)
			(layer "F.SilkS")
			(hide yes)
			(effects
				(font
					(size 0.7 0.7)
					(thickness 0.15)
				)
				(justify left bottom)
			)
		)
		(property "Value" "LED_G_0603_KP-1608CGCK"
			(at -0.001 1.599 0)
			(layer "F.Fab")
			(effects
				(font
					(size 0.7 0.7)
					(thickness 0.15)
				)
				(justify left bottom)
			)
		)
		(property "Datasheet" "http://www.farnell.com/datasheets/2045956.pdf"
			(at 0 0 0)
			(layer "F.Fab")
			(hide yes)
			(effects
				(font
					(size 1.27 1.27)
					(thickness 0.15)
				)
			)
		)
		(property "Author" "Antmicro"
			(at 0 0 0)
			(layer "F.Fab")
			(hide yes)
			(effects
				(font
					(size 1 1)
					(thickness 0.15)
				)
			)
		)
		(property "License" "Apache-2.0"
			(at 0 0 0)
			(layer "F.Fab")
			(hide yes)
			(effects
				(font
					(size 1 1)
					(thickness 0.15)
				)
			)
		)
		(property "MPN" "KP-1608CGCK"
			(at 0 0 0)
			(layer "F.Fab")
			(hide yes)
			(effects
				(font
					(size 1 1)
					(thickness 0.15)
				)
			)
		)
		(property "Manufacturer" "Kingbright"
			(at 0 0 0)
			(layer "F.Fab")
			(hide yes)
			(effects
				(font
					(size 1 1)
					(thickness 0.15)
				)
			)
		)
		(sheetname "/FPGA Config/")
		(sheetfile "fpga-config.kicad_sch")
		(attr smd)
		(fp_line
			(start -0.271 -0.349)
			(end 0.269 -0.349)
			(stroke
				(width 0.15)
				(type solid)
			)
			(layer "F.SilkS")
		)
		(fp_line
			(start -0.271 0.348)
			(end 0.269 0.348)
			(stroke
				(width 0.15)
				(type solid)
			)
			(layer "F.SilkS")
		)
		(fp_line
			(start -0.107 -0.201)
			(end -0.107 0.198)
			(stroke
				(width 0.1)
				(type solid)
			)
			(layer "F.SilkS")
		)
		(fp_line
			(start -0.107 -0.201)
			(end 0.092 -0.001)
			(stroke
				(width 0.1)
				(type solid)
			)
			(layer "F.SilkS")
		)
		(fp_line
			(start -0.107 -0.001)
			(end -0.291 -0.001)
			(stroke
				(width 0.1)
				(type solid)
			)
			(layer "F.SilkS")
		)
		(fp_line
			(start 0.092 -0.201)
			(end 0.092 0.198)
			(stroke
				(width 0.1)
				(type solid)
			)
			(layer "F.SilkS")
		)
		(fp_line
			(start 0.092 -0.001)
			(end -0.107 0.198)
			(stroke
				(width 0.1)
				(type solid)
			)
			(layer "F.SilkS")
		)
		(fp_line
			(start 0.092 -0.001)
			(end 0.292 -0.001)
			(stroke
				(width 0.1)
				(type solid)
			)
			(layer "F.SilkS")
		)
		(fp_line
			(start 1.249 0.319)
			(end 1.249 -0.321)
			(stroke
				(width 0.15)
				(type solid)
			)
			(layer "F.SilkS")
		)
		(fp_rect
			(start -1.2192 -0.6096)
			(end 1.27 0.6016)
			(stroke
				(width 0.05)
				(type solid)
			)
			(fill no)
			(layer "F.CrtYd")
		)
		(fp_line
			(start -0.849 0.025)
			(end -0.442 0.381)
			(stroke
				(width 0.15)
				(type solid)
			)
			(layer "F.Fab")
		)
		(fp_line
			(start -0.6 -0.001)
			(end -0.202 -0.001)
			(stroke
				(width 0.15)
				(type solid)
			)
			(layer "F.Fab")
		)
		(fp_line
			(start -0.202 -0.201)
			(end -0.202 -0.001)
			(stroke
				(width 0.15)
				(type solid)
			)
			(layer "F.Fab")
		)
		(fp_line
			(start -0.202 -0.001)
			(end -0.202 0.201)
			(stroke
				(width 0.15)
				(type solid)
			)
			(layer "F.Fab")
		)
		(fp_line
			(start -0.202 0.201)
			(end 0.1 -0.001)
			(stroke
				(width 0.15)
				(type solid)
			)
			(layer "F.Fab")
		)
		(fp_line
			(start 0.1 -0.001)
			(end -0.202 -0.201)
			(stroke
				(width 0.15)
				(type solid)
			)
			(layer "F.Fab")
		)
		(fp_line
			(start 0.198 -0.201)
			(end 0.198 -0.101)
			(stroke
				(width 0.15)
				(type solid)
			)
			(layer "F.Fab")
		)
		(fp_line
			(start 0.198 -0.001)
			(end 0.596 -0.001)
			(stroke
				(width 0.15)
				(type solid)
			)
			(layer "F.Fab")
		)
		(fp_line
			(start 0.198 0.201)
			(end 0.198 -0.101)
			(stroke
				(width 0.15)
				(type solid)
			)
			(layer "F.Fab")
		)
		(fp_rect
			(start -0.849 -0.401)
			(end 0.849 0.401)
			(stroke
				(width 0.15)
				(type solid)
			)
			(fill no)
			(layer "F.Fab")
		)
		(pad "1" smd rect
			(at -0.751 -0.001 180)
			(size 0.4 0.8)
			(layers "F.Cu" "F.Mask" "F.Paste")
			(net 200 "+3V3")
			(pinfunction "1")
			(pintype "passive")
		)
		(pad "2" smd rect
			(at 0.749 -0.001 180)
			(size 0.4 0.8)
			(layers "F.Cu" "F.Mask" "F.Paste")
			(net 304 "Net-(D1-Pad2)")
			(pinfunction "2")
			(pintype "passive")
		)
	)
	(footprint "antmicro-footprints:ESDA25P35-1U1M"
		(layer "F.Cu")
		(at 185.825 128.55 -90)
		(descr "DIODE SMD 0603")
		(tags "DIODE SMD 0603")
		(property "Reference" "D16"
			(at 0 -0.9 270)
			(layer "F.SilkS")
			(hide yes)
			(effects
				(font
					(size 0.7 0.7)
					(thickness 0.15)
				)
				(justify left bottom)
			)
		)
		(property "Value" "ESDA25P35-1U1M"
			(at 0 1.6 270)
			(layer "F.Fab")
			(effects
				(font
					(size 0.7 0.7)
					(thickness 0.15)
				)
				(justify left bottom)
			)
		)
		(property "Datasheet" "https://www.st.com/resource/en/datasheet/esda25p35-1u1m.pdf"
			(at 0 0 270)
			(layer "F.Fab")
			(hide yes)
			(effects
				(font
					(size 1.27 1.27)
					(thickness 0.15)
				)
			)
		)
		(property "Author" "Antmicro"
			(at 57.275 314.375 0)
			(layer "F.Fab")
			(hide yes)
			(effects
				(font
					(size 1 1)
					(thickness 0.15)
				)
			)
		)
		(property "License" "Apache-2.0"
			(at 57.275 314.375 0)
			(layer "F.Fab")
			(hide yes)
			(effects
				(font
					(size 1 1)
					(thickness 0.15)
				)
			)
		)
		(property "MPN" "ESDA25P35-1U1M"
			(at 57.275 314.375 0)
			(layer "F.Fab")
			(hide yes)
			(effects
				(font
					(size 1 1)
					(thickness 0.15)
				)
			)
		)
		(property "Manufacturer" "STMicroelectronics"
			(at 57.275 314.375 0)
			(layer "F.Fab")
			(hide yes)
			(effects
				(font
					(size 1 1)
					(thickness 0.15)
				)
			)
		)
		(sheetname "/Supply/")
		(sheetfile "supply.kicad_sch")
		(attr smd)
		(fp_line
			(start 1.25 0.5)
			(end 1.25 -0.498)
			(stroke
				(width 0.15)
				(type solid)
			)
			(layer "F.SilkS")
		)
		(fp_line
			(start -0.27 0.3)
			(end 0.27 0.3)
			(stroke
				(width 0.15)
				(type solid)
			)
			(layer "F.SilkS")
		)
		(fp_line
			(start -0.27 -0.3)
			(end 0.27 -0.3)
			(stroke
				(width 0.15)
				(type solid)
			)
			(layer "F.SilkS")
		)
		(fp_rect
			(start 1.31 0.7)
			(end -1.31 -0.7)
			(stroke
				(width 0.05)
				(type solid)
			)
			(fill no)
			(layer "F.CrtYd")
		)
		(fp_line
			(start -0.201 0.202)
			(end 0.101 0)
			(stroke
				(width 0.15)
				(type solid)
			)
			(layer "F.Fab")
		)
		(fp_line
			(start 0.199 0.202)
			(end 0.199 -0.1)
			(stroke
				(width 0.15)
				(type solid)
			)
			(layer "F.Fab")
		)
		(fp_line
			(start -0.599 0)
			(end -0.201 0)
			(stroke
				(width 0.15)
				(type solid)
			)
			(layer "F.Fab")
		)
		(fp_line
			(start -0.201 0)
			(end -0.201 0.202)
			(stroke
				(width 0.15)
				(type solid)
			)
			(layer "F.Fab")
		)
		(fp_line
			(start 0.101 0)
			(end -0.201 -0.2)
			(stroke
				(width 0.15)
				(type solid)
			)
			(layer "F.Fab")
		)
		(fp_line
			(start 0.199 0)
			(end 0.597 0)
			(stroke
				(width 0.15)
				(type solid)
			)
			(layer "F.Fab")
		)
		(fp_line
			(start -0.201 -0.2)
			(end -0.201 0)
			(stroke
				(width 0.15)
				(type solid)
			)
			(layer "F.Fab")
		)
		(fp_line
			(start 0.199 -0.2)
			(end 0.199 -0.1)
			(stroke
				(width 0.15)
				(type solid)
			)
			(layer "F.Fab")
		)
		(fp_rect
			(start -0.848 -0.4)
			(end 0.85 0.402)
			(stroke
				(width 0.15)
				(type solid)
			)
			(fill no)
			(layer "F.Fab")
		)
		(pad "1" smd rect
			(at -0.75 0 90)
			(size 0.8 0.8)
			(layers "F.Cu" "F.Mask" "F.Paste")
			(net 1 "GND")
			(pinfunction "K")
			(pintype "passive")
		)
		(pad "2" smd rect
			(at 0.75 0 90)
			(size 0.8 0.8)
			(layers "F.Cu" "F.Mask" "F.Paste")
			(net 595 "/Supply/12V_aux_fused")
			(pinfunction "A")
			(pintype "passive")
		)
	)
)
